FILE_TYPE=LIBRARY_PARTS;
primitive '74LVC2G08DP';
  pin
    'VCC':
      PIN_NUMBER='(8,0)';
      PINUSE='POWER';
      NO_LOAD_CHECK='Both';
      NO_IO_CHECK='Both';
      NO_ASSERT_CHECK='TRUE';
      NO_DIR_CHECK='TRUE';
      ALLOW_CONNECT='TRUE';
    'GND':
      PIN_NUMBER='(4,0)';
      PINUSE='POWER';
      NO_LOAD_CHECK='Both';
      NO_IO_CHECK='Both';
      NO_ASSERT_CHECK='TRUE';
      NO_DIR_CHECK='TRUE';
      ALLOW_CONNECT='TRUE';
    '1A':
      PIN_NUMBER='(1,0)';
      INPUT_LOAD='(-0.01,0.01)';
    '1B':
      PIN_NUMBER='(2,0)';
      INPUT_LOAD='(-0.01,0.01)';
    '1Y':
      PIN_NUMBER='(7,0)';
      OUTPUT_LOAD='(1.0,-1.0)';
    '2A':
      PIN_NUMBER='(0,5)';
      INPUT_LOAD='(-0.01,0.01)';
    '2B':
      PIN_NUMBER='(0,6)';
      INPUT_LOAD='(-0.01,0.01)';
    '2Y':
      PIN_NUMBER='(0,3)';
      OUTPUT_LOAD='(1.0,-1.0)';
  end_pin;
  body
    PART_NAME='74LVC2G08DP';
    BODY_NAME='74LVC2G08DP';
    PHYS_DES_PREFIX='U';
    CLASS='IC';
  end_body;
end_primitive;

END.
